(kicad_pcb
	(version 20241229)
	(generator "pcbnew")
	(generator_version "9.0")
	(general
		(thickness 1.62)
		(legacy_teardrops no)
	)
	(paper "A3")
	(title_block
		(title "COM Express 7 Baseboard")
		(date "2025-02-04")
		(rev "1.1.2")
		(company "Antmicro Ltd")
		(comment 1 "www.antmicro.com")
		(comment 9 "footprints 54-58 of 802")
	)
	(layers
		(0 "F.Cu" signal)
		(4 "In1.Cu" signal)
		(6 "In2.Cu" signal)
		(8 "In3.Cu" signal)
		(10 "In4.Cu" signal)
		(12 "In5.Cu" signal)
		(14 "In6.Cu" signal)
		(2 "B.Cu" signal)
		(9 "F.Adhes" user "F.Adhesive")
		(11 "B.Adhes" user "B.Adhesive")
		(13 "F.Paste" user)
		(15 "B.Paste" user)
		(5 "F.SilkS" user "F.Silkscreen")
		(7 "B.SilkS" user "B.Silkscreen")
		(1 "F.Mask" user)
		(3 "B.Mask" user)
		(17 "Dwgs.User" user "User.Drawings")
		(19 "Cmts.User" user "User.Comments")
		(21 "Eco1.User" user "User.Eco1")
		(23 "Eco2.User" user "User.Eco2")
		(25 "Edge.Cuts" user)
		(27 "Margin" user)
		(31 "F.CrtYd" user "F.Courtyard")
		(29 "B.CrtYd" user "B.Courtyard")
		(35 "F.Fab" user)
		(33 "B.Fab" user)
	)
	(footprint "antmicro-footprints:C_0603_1608Metric"
		(layer "F.Cu")
		(at 219.3 159.9 180)
		(descr "Capacitor SMD 0603")
		(tags "capacitor 0603")
		(property "Reference" "C95"
			(at -3.42 0.39 0)
			(layer "F.SilkS")
			(effects
				(font
					(size 0.7 0.7)
					(thickness 0.15)
				)
				(justify right top)
			)
		)
		(property "Value" "C_22u_16V_0603"
			(at -54.09257 -1.454712 0)
			(layer "F.Fab")
			(hide yes)
			(effects
				(font
					(size 0.7 0.7)
					(thickness 0.15)
				)
				(justify right top)
			)
		)
		(property "Datasheet" "https://product.samsungsem.com/mlcc/CL10A226MO7JZN.do"
			(at 0 0 0)
			(layer "F.Fab")
			(hide yes)
			(effects
				(font
					(size 1.27 1.27)
					(thickness 0.15)
				)
			)
		)
		(property "Author" "Antmicro"
			(at 348.085 -28.515 90)
			(layer "F.Fab")
			(hide yes)
			(effects
				(font
					(size 1 1)
					(thickness 0.15)
				)
			)
		)
		(property "Dielectric" ""
			(at 348.085 -28.515 90)
			(layer "F.Fab")
			(hide yes)
			(effects
				(font
					(size 1 1)
					(thickness 0.15)
				)
			)
		)
		(property "License" "Apache-2.0"
			(at 348.085 -28.515 90)
			(layer "F.Fab")
			(hide yes)
			(effects
				(font
					(size 1 1)
					(thickness 0.15)
				)
			)
		)
		(property "MPN" "CL10A226MO7JZNC"
			(at 348.085 -28.515 90)
			(layer "F.Fab")
			(hide yes)
			(effects
				(font
					(size 1 1)
					(thickness 0.15)
				)
			)
		)
		(property "Manufacturer" "Samsung Electro-Mechanics"
			(at 348.085 -28.515 90)
			(layer "F.Fab")
			(hide yes)
			(effects
				(font
					(size 1 1)
					(thickness 0.15)
				)
			)
		)
		(property "Public" "False"
			(at 348.085 -28.515 90)
			(layer "F.Fab")
			(hide yes)
			(effects
				(font
					(size 1 1)
					(thickness 0.15)
				)
			)
		)
		(property "Val" "22u"
			(at 348.085 -28.515 90)
			(layer "F.Fab")
			(hide yes)
			(effects
				(font
					(size 1 1)
					(thickness 0.15)
				)
			)
		)
		(property "Voltage" "16V"
			(at 348.085 -28.515 90)
			(layer "F.Fab")
			(hide yes)
			(effects
				(font
					(size 1 1)
					(thickness 0.15)
				)
			)
		)
		(sheetname "Com Express 7 MGMT")
		(sheetfile "com_express_7_mgmt.kicad_sch")
		(attr smd)
		(fp_line
			(start -0.15 0.4)
			(end 0.15 0.4)
			(stroke
				(width 0.15)
				(type solid)
			)
			(layer "F.SilkS")
		)
		(fp_line
			(start -0.15 -0.4)
			(end 0.15 -0.4)
			(stroke
				(width 0.15)
				(type solid)
			)
			(layer "F.SilkS")
		)
		(fp_rect
			(start -1.25 -0.65)
			(end 1.25 0.65)
			(stroke
				(width 0.05)
				(type solid)
			)
			(fill no)
			(layer "F.CrtYd")
		)
		(fp_rect
			(start -0.8 -0.4)
			(end 0.8 0.4)
			(stroke
				(width 0.15)
				(type solid)
			)
			(fill no)
			(layer "F.Fab")
		)
		(pad "1" smd roundrect
			(at -0.7 0 180)
			(size 0.8 1)
			(layers "F.Cu" "F.Mask" "F.Paste")
			(roundrect_rratio 0.2)
			(net 1 "GND")
			(pintype "passive")
			(teardrops
				(best_length_ratio 0.2)
				(max_length 1)
				(best_width_ratio 0.9)
				(max_width 2)
				(curved_edges yes)
				(filter_ratio 0.9)
				(enabled yes)
				(allow_two_segments yes)
				(prefer_zone_connections yes)
			)
		)
		(pad "2" smd roundrect
			(at 0.7 0 180)
			(size 0.8 1)
			(layers "F.Cu" "F.Mask" "F.Paste")
			(roundrect_rratio 0.2)
			(net 77 "+5V_AON")
			(pintype "passive")
			(teardrops
				(best_length_ratio 0.2)
				(max_length 1)
				(best_width_ratio 0.9)
				(max_width 2)
				(curved_edges yes)
				(filter_ratio 0.9)
				(enabled yes)
				(allow_two_segments yes)
				(prefer_zone_connections yes)
			)
		)
	)
	(footprint "antmicro-footprints:R_0402_1005Metric"
		(layer "F.Cu")
		(at 124.21 145.05)
		(descr "Resistor SMD 0402")
		(tags "resistor SMD 0402")
		(property "Reference" "R282"
			(at -3.61 0.46 0)
			(layer "F.SilkS")
			(effects
				(font
					(size 0.7 0.7)
					(thickness 0.15)
				)
				(justify left bottom)
			)
		)
		(property "Value" "R_0R_0402"
			(at -1.011843 1.772047 0)
			(layer "F.Fab")
			(effects
				(font
					(size 0.7 0.7)
					(thickness 0.15)
				)
				(justify left bottom)
			)
		)
		(property "Datasheet" "https://industrial.panasonic.com/cdbs/www-data/pdf/RDA0000/AOA0000C301.pdf"
			(at 0 0 0)
			(layer "F.Fab")
			(hide yes)
			(effects
				(font
					(size 1.27 1.27)
					(thickness 0.15)
				)
			)
		)
		(property "Author" "Antmicro"
			(at 0 0 0)
			(layer "F.Fab")
			(hide yes)
			(effects
				(font
					(size 1 1)
					(thickness 0.15)
				)
			)
		)
		(property "Current" "1A"
			(at 0 0 0)
			(layer "F.Fab")
			(hide yes)
			(effects
				(font
					(size 1 1)
					(thickness 0.15)
				)
			)
		)
		(property "License" "Apache-2.0"
			(at 0 0 0)
			(layer "F.Fab")
			(hide yes)
			(effects
				(font
					(size 1 1)
					(thickness 0.15)
				)
			)
		)
		(property "MPN" "ERJ2GE0R00X"
			(at 0 0 0)
			(layer "F.Fab")
			(hide yes)
			(effects
				(font
					(size 1 1)
					(thickness 0.15)
				)
			)
		)
		(property "Manufacturer" "Panasonic"
			(at 0 0 0)
			(layer "F.Fab")
			(hide yes)
			(effects
				(font
					(size 1 1)
					(thickness 0.15)
				)
			)
		)
		(property "Public" "False"
			(at 0 0 0)
			(layer "F.Fab")
			(hide yes)
			(effects
				(font
					(size 1 1)
					(thickness 0.15)
				)
			)
		)
		(property "Tolerance" ""
			(at 0 0 0)
			(layer "F.Fab")
			(hide yes)
			(effects
				(font
					(size 1 1)
					(thickness 0.15)
				)
			)
		)
		(property "Val" "0R"
			(at 0 0 0)
			(layer "F.Fab")
			(hide yes)
			(effects
				(font
					(size 1 1)
					(thickness 0.15)
				)
			)
		)
		(sheetname "KR to SFI #2")
		(sheetfile "kr_sfi.kicad_sch")
		(attr smd)
		(fp_rect
			(start -0.925 -0.47)
			(end 0.925 0.47)
			(stroke
				(width 0.05)
				(type default)
			)
			(fill no)
			(layer "F.CrtYd")
		)
		(fp_rect
			(start -0.5 -0.25)
			(end 0.5 0.25)
			(stroke
				(width 0.15)
				(type solid)
			)
			(fill no)
			(layer "F.Fab")
		)
		(pad "1" smd roundrect
			(at -0.48 0)
			(size 0.59 0.64)
			(layers "F.Cu" "F.Mask" "F.Paste")
			(roundrect_rratio 0.25)
			(net 671 "/2xSFP+/KR to SFI #2/MDC_R")
			(pintype "passive")
			(teardrops
				(best_length_ratio 0.2)
				(max_length 1)
				(best_width_ratio 0.9)
				(max_width 2)
				(curved_edges yes)
				(filter_ratio 0.9)
				(enabled yes)
				(allow_two_segments yes)
				(prefer_zone_connections yes)
			)
		)
		(pad "2" smd roundrect
			(at 0.48 0)
			(size 0.59 0.64)
			(layers "F.Cu" "F.Mask" "F.Paste")
			(roundrect_rratio 0.25)
			(net 672 "/2xSFP+/KR to SFI #2/MDC")
			(pintype "passive")
			(teardrops
				(best_length_ratio 0.2)
				(max_length 1)
				(best_width_ratio 0.9)
				(max_width 2)
				(curved_edges yes)
				(filter_ratio 0.9)
				(enabled yes)
				(allow_two_segments yes)
				(prefer_zone_connections yes)
			)
		)
	)
	(footprint "antmicro-footprints:Conn_Molex_KK_1x4_0470531000"
		(layer "F.Cu")
		(at 238.780707 71.86 180)
		(property "Reference" "J11"
			(at 7.159999 -3.8 0)
			(layer "F.SilkS")
			(effects
				(font
					(size 0.7 0.7)
					(thickness 0.15)
				)
				(justify right bottom)
			)
		)
		(property "Value" "Molex_KK_1x4_0470531000"
			(at 0 4.7 0)
			(layer "F.Fab")
			(effects
				(font
					(size 0.7 0.7)
					(thickness 0.15)
				)
				(justify right bottom)
			)
		)
		(property "Datasheet" "https://tools.molex.com/pdm_docs/sd/470531000_sd.pdf"
			(at 0 0 180)
			(layer "F.Fab")
			(hide yes)
			(effects
				(font
					(size 1.27 1.27)
					(thickness 0.15)
				)
			)
		)
		(property "Author" "Antmicro"
			(at 477.561414 143.72 0)
			(layer "F.Fab")
			(hide yes)
			(effects
				(font
					(size 1 1)
					(thickness 0.15)
				)
			)
		)
		(property "License" "Apache-2.0"
			(at 477.561414 143.72 0)
			(layer "F.Fab")
			(hide yes)
			(effects
				(font
					(size 1 1)
					(thickness 0.15)
				)
			)
		)
		(property "MPN" "0470531000"
			(at 477.561414 143.72 0)
			(layer "F.Fab")
			(hide yes)
			(effects
				(font
					(size 1 1)
					(thickness 0.15)
				)
			)
		)
		(property "Manufacturer" "Molex"
			(at 477.561414 143.72 0)
			(layer "F.Fab")
			(hide yes)
			(effects
				(font
					(size 1 1)
					(thickness 0.15)
				)
			)
		)
		(sheetname "Misc")
		(sheetfile "misc.kicad_sch")
		(attr through_hole)
		(fp_line
			(start 8.95 3.4)
			(end -1.35 3.4)
			(stroke
				(width 0.15)
				(type solid)
			)
			(layer "F.SilkS")
		)
		(fp_line
			(start 8.95 -2.55)
			(end 8.95 3.4)
			(stroke
				(width 0.15)
				(type solid)
			)
			(layer "F.SilkS")
		)
		(fp_line
			(start 5.75 -2.55)
			(end 8.95 -2.55)
			(stroke
				(width 0.15)
				(type solid)
			)
			(layer "F.SilkS")
		)
		(fp_line
			(start 5.08 2.29)
			(end 5.08 3.3)
			(stroke
				(width 0.15)
				(type solid)
			)
			(layer "F.SilkS")
		)
		(fp_line
			(start 0 3.3)
			(end 0 2.29)
			(stroke
				(width 0.15)
				(type solid)
			)
			(layer "F.SilkS")
		)
		(fp_line
			(start 0 2.29)
			(end 5.08 2.29)
			(stroke
				(width 0.15)
				(type solid)
			)
			(layer "F.SilkS")
		)
		(fp_line
			(start -1.35 3.4)
			(end -1.35 -2.6)
			(stroke
				(width 0.15)
				(type solid)
			)
			(layer "F.SilkS")
		)
		(fp_line
			(start -1.35 -2.6)
			(end 4.4 -2.6)
			(stroke
				(width 0.15)
				(type solid)
			)
			(layer "F.SilkS")
		)
		(fp_circle
			(center 0 -3)
			(end 0.05 -3)
			(stroke
				(width 0.15)
				(type solid)
			)
			(fill yes)
			(layer "F.SilkS")
		)
		(fp_rect
			(start -1.54 -2.96)
			(end 9.16 3.55)
			(stroke
				(width 0.05)
				(type solid)
			)
			(fill no)
			(layer "F.CrtYd")
		)
		(fp_line
			(start 8.85 3.3)
			(end -1.2 3.3)
			(stroke
				(width 0.15)
				(type solid)
			)
			(layer "F.Fab")
		)
		(fp_line
			(start 8.85 -2.5)
			(end 8.85 3.3)
			(stroke
				(width 0.15)
				(type solid)
			)
			(layer "F.Fab")
		)
		(fp_line
			(start 5.75 -2.5)
			(end 8.85 -2.5)
			(stroke
				(width 0.15)
				(type solid)
			)
			(layer "F.Fab")
		)
		(fp_line
			(start 5.1 3.3)
			(end 5.1 2.3)
			(stroke
				(width 0.15)
				(type solid)
			)
			(layer "F.Fab")
		)
		(fp_line
			(start 5.1 2.3)
			(end 0 2.3)
			(stroke
				(width 0.15)
				(type solid)
			)
			(layer "F.Fab")
		)
		(fp_line
			(start 0 2.3)
			(end 0 3.3)
			(stroke
				(width 0.15)
				(type solid)
			)
			(layer "F.Fab")
		)
		(fp_line
			(start -1.2 3.3)
			(end -1.25 3.3)
			(stroke
				(width 0.15)
				(type solid)
			)
			(layer "F.Fab")
		)
		(fp_line
			(start -1.25 3.3)
			(end -1.25 -2.5)
			(stroke
				(width 0.15)
				(type solid)
			)
			(layer "F.Fab")
		)
		(fp_line
			(start -1.25 -2.5)
			(end 4.4 -2.5)
			(stroke
				(width 0.15)
				(type solid)
			)
			(layer "F.Fab")
		)
		(pad "" np_thru_hole circle
			(at 5.08 -2.16 270)
			(size 1.1 1.1)
			(drill 1.1)
			(layers "*.Cu" "*.Mask")
		)
		(pad "1" thru_hole rect
			(at 0 0 270)
			(size 2.03 1.73)
			(drill 1.02)
			(layers "*.Cu" "*.Mask")
			(remove_unused_layers no)
			(net 1 "GND")
			(pintype "passive")
			(teardrops
				(best_length_ratio 0.2)
				(max_length 1)
				(best_width_ratio 0.9)
				(max_width 2)
				(curved_edges yes)
				(filter_ratio 0.9)
				(enabled yes)
				(allow_two_segments yes)
				(prefer_zone_connections yes)
			)
		)
		(pad "2" thru_hole oval
			(at 2.54 0 270)
			(size 2.03 1.73)
			(drill 1.02)
			(layers "*.Cu" "*.Mask")
			(remove_unused_layers no)
			(net 81 "/Misc/FAN_12V")
			(pintype "passive")
			(teardrops
				(best_length_ratio 0.2)
				(max_length 1)
				(best_width_ratio 0.9)
				(max_width 2)
				(curved_edges yes)
				(filter_ratio 0.9)
				(enabled yes)
				(allow_two_segments yes)
				(prefer_zone_connections yes)
			)
		)
		(pad "3" thru_hole oval
			(at 5.08 0 270)
			(size 2.03 1.73)
			(drill 1.02)
			(layers "*.Cu" "*.Mask")
			(remove_unused_layers no)
			(net 283 "/Misc/TACH_{C5V}")
			(pintype "passive")
			(teardrops
				(best_length_ratio 0.2)
				(max_length 1)
				(best_width_ratio 0.9)
				(max_width 2)
				(curved_edges yes)
				(filter_ratio 0.9)
				(enabled yes)
				(allow_two_segments yes)
				(prefer_zone_connections yes)
			)
		)
		(pad "4" thru_hole oval
			(at 7.62 0 270)
			(size 2.03 1.73)
			(drill 1.02)
			(layers "*.Cu" "*.Mask")
			(remove_unused_layers no)
			(net 284 "/Misc/PWM_{C5V}")
			(pintype "passive")
			(teardrops
				(best_length_ratio 0.2)
				(max_length 1)
				(best_width_ratio 0.9)
				(max_width 2)
				(curved_edges yes)
				(filter_ratio 0.9)
				(enabled yes)
				(allow_two_segments yes)
				(prefer_zone_connections yes)
			)
		)
	)
	(footprint "antmicro-footprints:TP_SMD_0.75mm"
		(layer "F.Cu")
		(at 134.94 128.71)
		(property "Reference" "TP79"
			(at 0.51 -3.3 90)
			(layer "F.SilkS")
			(effects
				(font
					(size 0.7 0.7)
					(thickness 0.15)
				)
				(justify left bottom)
			)
		)
		(property "Value" "TP_0.75mm_SMD"
			(at 0 1.2 0)
			(layer "F.Fab")
			(effects
				(font
					(size 0.7 0.7)
					(thickness 0.15)
				)
				(justify left bottom)
			)
		)
		(property "Author" "Antmicro"
			(at 0 0 0)
			(layer "F.Fab")
			(hide yes)
			(effects
				(font
					(size 1 1)
					(thickness 0.15)
				)
			)
		)
		(property "License" "Apache-2.0"
			(at 0 0 0)
			(layer "F.Fab")
			(hide yes)
			(effects
				(font
					(size 1 1)
					(thickness 0.15)
				)
			)
		)
		(property "MPN" ""
			(at 0 0 0)
			(layer "F.Fab")
			(hide yes)
			(effects
				(font
					(size 1 1)
					(thickness 0.15)
				)
			)
		)
		(property "Manufacturer" ""
			(at 0 0 0)
			(layer "F.Fab")
			(hide yes)
			(effects
				(font
					(size 1 1)
					(thickness 0.15)
				)
			)
		)
		(property "Public" "False"
			(at 0 0 0)
			(layer "F.Fab")
			(hide yes)
			(effects
				(font
					(size 1 1)
					(thickness 0.15)
				)
			)
		)
		(sheetname "KR to SFI #2")
		(sheetfile "kr_sfi.kicad_sch")
		(attr exclude_from_pos_files exclude_from_bom)
		(fp_circle
			(center 0 0)
			(end 0.475 0)
			(stroke
				(width 0.05)
				(type default)
			)
			(fill no)
			(layer "F.CrtYd")
		)
		(pad "1" smd circle
			(at 0 0)
			(size 0.75 0.75)
			(layers "F.Cu" "F.Mask")
			(net 742 "/2xSFP+/KR to SFI #2/TDI")
			(pinfunction "1")
			(pintype "passive")
			(teardrops
				(best_length_ratio 0.4)
				(max_length 1)
				(best_width_ratio 0.9)
				(max_width 2)
				(curved_edges yes)
				(filter_ratio 0.9)
				(enabled yes)
				(allow_two_segments yes)
				(prefer_zone_connections yes)
			)
		)
	)
	(footprint "antmicro-footprints:R_0402_1005Metric"
		(layer "F.Cu")
		(at 292.5 96.16)
		(descr "Resistor SMD 0402")
		(tags "resistor SMD 0402")
		(property "Reference" "R118"
			(at -1.4 -0.5 0)
			(layer "F.SilkS")
			(effects
				(font
					(size 0.7 0.7)
					(thickness 0.15)
				)
				(justify left bottom)
			)
		)
		(property "Value" "R_100k_0402"
			(at -1.011843 1.772047 0)
			(layer "F.Fab")
			(effects
				(font
					(size 0.7 0.7)
					(thickness 0.15)
				)
				(justify left bottom)
			)
		)
		(property "Datasheet" "https://www.bourns.com/docs/product-datasheets/cr.pdf"
			(at 0 0 0)
			(layer "F.Fab")
			(hide yes)
			(effects
				(font
					(size 1.27 1.27)
					(thickness 0.15)
				)
			)
		)
		(property "Author" "Antmicro"
			(at 0 0 0)
			(layer "F.Fab")
			(hide yes)
			(effects
				(font
					(size 1 1)
					(thickness 0.15)
				)
			)
		)
		(property "License" "Apache-2.0"
			(at 0 0 0)
			(layer "F.Fab")
			(hide yes)
			(effects
				(font
					(size 1 1)
					(thickness 0.15)
				)
			)
		)
		(property "MPN" "CR0402-FX-1003GLF"
			(at 0 0 0)
			(layer "F.Fab")
			(hide yes)
			(effects
				(font
					(size 1 1)
					(thickness 0.15)
				)
			)
		)
		(property "Manufacturer" "Bourns"
			(at 0 0 0)
			(layer "F.Fab")
			(hide yes)
			(effects
				(font
					(size 1 1)
					(thickness 0.15)
				)
			)
		)
		(property "Public" "False"
			(at 0 0 0)
			(layer "F.Fab")
			(hide yes)
			(effects
				(font
					(size 1 1)
					(thickness 0.15)
				)
			)
		)
		(property "Tolerance" "1%"
			(at 0 0 0)
			(layer "F.Fab")
			(hide yes)
			(effects
				(font
					(size 1 1)
					(thickness 0.15)
				)
			)
		)
		(property "Val" "100k"
			(at 0 0 0)
			(layer "F.Fab")
			(hide yes)
			(effects
				(font
					(size 1 1)
					(thickness 0.15)
				)
			)
		)
		(sheetname "Power")
		(sheetfile "power.kicad_sch")
		(attr smd)
		(fp_rect
			(start -0.925 -0.47)
			(end 0.925 0.47)
			(stroke
				(width 0.05)
				(type default)
			)
			(fill no)
			(layer "F.CrtYd")
		)
		(fp_rect
			(start -0.5 -0.25)
			(end 0.5 0.25)
			(stroke
				(width 0.15)
				(type solid)
			)
			(fill no)
			(layer "F.Fab")
		)
		(pad "1" smd roundrect
			(at -0.48 0)
			(size 0.59 0.64)
			(layers "F.Cu" "F.Mask" "F.Paste")
			(roundrect_rratio 0.25)
			(net 536 "Net-(Q3-D)")
			(pintype "passive")
			(teardrops
				(best_length_ratio 0.2)
				(max_length 1)
				(best_width_ratio 0.9)
				(max_width 2)
				(curved_edges yes)
				(filter_ratio 0.9)
				(enabled yes)
				(allow_two_segments yes)
				(prefer_zone_connections yes)
			)
		)
		(pad "2" smd roundrect
			(at 0.48 0)
			(size 0.59 0.64)
			(layers "F.Cu" "F.Mask" "F.Paste")
			(roundrect_rratio 0.25)
			(net 77 "+5V_AON")
			(pintype "passive")
			(teardrops
				(best_length_ratio 0.2)
				(max_length 1)
				(best_width_ratio 0.9)
				(max_width 2)
				(curved_edges yes)
				(filter_ratio 0.9)
				(enabled yes)
				(allow_two_segments yes)
				(prefer_zone_connections yes)
			)
		)
	)
)
